(kicad_pcb
	(version 20241229)
	(generator "pcbnew")
	(generator_version "9.0")
	(general
		(thickness 1.711)
		(legacy_teardrops no)
	)
	(paper "A4")
	(title_block
		(title "Antmicro Baseboard for Jetson AGX Thor")
		(date "2026-02-18")
		(rev "1.1.0")
		(company "Antmicro Ltd")
		(comment 1 "www.antmicro.com")
		(comment 9 "footprints 788-792 of 1170")
	)
	(layers
		(0 "F.Cu" signal)
		(4 "In1.Cu" signal)
		(6 "In2.Cu" signal)
		(8 "In3.Cu" signal)
		(10 "In4.Cu" jumper)
		(12 "In5.Cu" signal)
		(14 "In6.Cu" signal)
		(16 "In7.Cu" signal)
		(18 "In8.Cu" signal)
		(2 "B.Cu" signal)
		(9 "F.Adhes" user "F.Adhesive")
		(11 "B.Adhes" user "B.Adhesive")
		(13 "F.Paste" user)
		(15 "B.Paste" user)
		(5 "F.SilkS" user "F.Silkscreen")
		(7 "B.SilkS" user "B.Silkscreen")
		(1 "F.Mask" user)
		(3 "B.Mask" user)
		(17 "Dwgs.User" user "User.Drawings")
		(19 "Cmts.User" user "User.Comments")
		(21 "Eco1.User" user "User.Eco1")
		(23 "Eco2.User" user "User.Eco2")
		(25 "Edge.Cuts" user)
		(27 "Margin" user)
		(31 "F.CrtYd" user "F.Courtyard")
		(29 "B.CrtYd" user "B.Courtyard")
		(35 "F.Fab" user)
		(33 "B.Fab" user)
	)
	(footprint "antmicro-footprints:SOT-523"
		(layer "B.Cu")
		(at 223.2 109.2 180)
		(property "Reference" "Q15"
			(at -1.1 -1.2 90)
			(layer "B.SilkS")
			(effects
				(font
					(size 0.7 0.7)
					(thickness 0.15)
				)
				(justify left bottom mirror)
			)
		)
		(property "Value" "DMG1012T-7"
			(at 0.1 -1.824 0)
			(layer "B.Fab")
			(effects
				(font
					(size 0.7 0.7)
					(thickness 0.15)
				)
				(justify left bottom mirror)
			)
		)
		(property "Datasheet" "https://www.diodes.com/assets/Datasheets/ds31783.pdf"
			(at 0 0 0)
			(layer "B.Fab")
			(hide yes)
			(effects
				(font
					(size 1.27 1.27)
					(thickness 0.15)
				)
				(justify mirror)
			)
		)
		(property "Description" "Power MOSFET, N Channel, 20 V, 630 mA, 0.3 ohm, SOT-523, Surface Mount"
			(at 0 0 0)
			(layer "B.Fab")
			(hide yes)
			(effects
				(font
					(size 1.27 1.27)
					(thickness 0.15)
				)
				(justify mirror)
			)
		)
		(property "MPN" "DMG1012T-7"
			(at 0 0 0)
			(unlocked yes)
			(layer "B.Fab")
			(hide yes)
			(effects
				(font
					(size 1 1)
					(thickness 0.15)
				)
				(justify mirror)
			)
		)
		(property "Manufacturer" "Diodes Incorporated"
			(at 0 0 0)
			(unlocked yes)
			(layer "B.Fab")
			(hide yes)
			(effects
				(font
					(size 1 1)
					(thickness 0.15)
				)
				(justify mirror)
			)
		)
		(property "Author" "Antmicro"
			(at 0 0 0)
			(unlocked yes)
			(layer "B.Fab")
			(hide yes)
			(effects
				(font
					(size 1 1)
					(thickness 0.15)
				)
				(justify mirror)
			)
		)
		(property "License" "Apache-2.0"
			(at 0 0 0)
			(unlocked yes)
			(layer "B.Fab")
			(hide yes)
			(effects
				(font
					(size 1 1)
					(thickness 0.15)
				)
				(justify mirror)
			)
		)
		(sheetname "/Recovery USB/")
		(sheetfile "recovery_usb.kicad_sch")
		(attr smd)
		(fp_line
			(start -0.277 0.551)
			(end -0.277 0.75)
			(stroke
				(width 0.15)
				(type solid)
			)
			(layer "B.SilkS")
		)
		(fp_line
			(start -0.725 0.551)
			(end -0.277 0.551)
			(stroke
				(width 0.15)
				(type solid)
			)
			(layer "B.SilkS")
		)
		(fp_line
			(start -0.927 0.351)
			(end -0.725 0.551)
			(stroke
				(width 0.15)
				(type solid)
			)
			(layer "B.SilkS")
		)
		(fp_line
			(start -0.927 0.051)
			(end -0.927 0.351)
			(stroke
				(width 0.15)
				(type solid)
			)
			(layer "B.SilkS")
		)
		(fp_circle
			(center -0.9652 -0.9652)
			(end -0.9152 -0.9652)
			(stroke
				(width 0.15)
				(type solid)
			)
			(fill yes)
			(layer "B.SilkS")
		)
		(fp_line
			(start 1.1 1.16)
			(end 1.1 -1.15)
			(stroke
				(width 0.05)
				(type solid)
			)
			(layer "B.CrtYd")
		)
		(fp_line
			(start -1.12 1.16)
			(end 1.1 1.16)
			(stroke
				(width 0.05)
				(type solid)
			)
			(layer "B.CrtYd")
		)
		(fp_line
			(start -1.12 1.16)
			(end -1.12 -1.15)
			(stroke
				(width 0.05)
				(type solid)
			)
			(layer "B.CrtYd")
		)
		(fp_line
			(start -1.12 -1.15)
			(end 1.1 -1.15)
			(stroke
				(width 0.05)
				(type solid)
			)
			(layer "B.CrtYd")
		)
		(fp_line
			(start 0.8 0.425)
			(end 0.8 -0.424)
			(stroke
				(width 0.15)
				(type solid)
			)
			(layer "B.Fab")
		)
		(fp_line
			(start 0.8 0.425)
			(end -0.652 0.425)
			(stroke
				(width 0.15)
				(type solid)
			)
			(layer "B.Fab")
		)
		(fp_line
			(start 0.8 -0.424)
			(end -0.802 -0.424)
			(stroke
				(width 0.15)
				(type solid)
			)
			(layer "B.Fab")
		)
		(fp_line
			(start -0.652 0.425)
			(end -0.802 0.276)
			(stroke
				(width 0.15)
				(type solid)
			)
			(layer "B.Fab")
		)
		(fp_line
			(start -0.802 0.276)
			(end -0.802 -0.424)
			(stroke
				(width 0.15)
				(type solid)
			)
			(layer "B.Fab")
		)
		(fp_circle
			(center -0.9652 -0.9652)
			(end -0.9144 -0.9652)
			(stroke
				(width 0.15)
				(type solid)
			)
			(fill no)
			(layer "B.Fab")
		)
		(fp_text user "${REFERENCE}"
			(at -1.12 -3.824 0)
			(layer "B.Fab")
			(effects
				(font
					(size 0.7 0.7)
					(thickness 0.15)
				)
				(justify left bottom mirror)
			)
		)
		(fp_text user "License: Apache-2.0"
			(at -1.12 -5.024 0)
			(layer "B.Fab")
			(effects
				(font
					(size 0.7 0.7)
					(thickness 0.15)
				)
				(justify left bottom mirror)
			)
		)
		(fp_text user "Author: Antmicro"
			(at -1.12 -6.224 0)
			(layer "B.Fab")
			(effects
				(font
					(size 0.7 0.7)
					(thickness 0.15)
				)
				(justify left bottom mirror)
			)
		)
		(pad "1" smd rect
			(at -0.5 -0.65 180)
			(size 0.4 0.51)
			(layers "B.Cu" "B.Mask" "B.Paste")
			(net 287 "/Recovery USB/USBC2_VBUS")
			(pinfunction "G")
			(pintype "input")
		)
		(pad "2" smd rect
			(at 0.498 -0.65 180)
			(size 0.4 0.51)
			(layers "B.Cu" "B.Mask" "B.Paste")
			(net 1 "GND")
			(pinfunction "S")
			(pintype "passive")
		)
		(pad "3" smd rect
			(at 0 0.652 180)
			(size 0.4 0.51)
			(layers "B.Cu" "B.Mask" "B.Paste")
			(net 1018 "/Recovery USB/USBC2_VBUS_DET")
			(pinfunction "D")
			(pintype "passive")
		)
	)
	(footprint "antmicro-footprints:TP_SMD_0.75mm"
		(layer "B.Cu")
		(at 63.5 121.999999)
		(property "Reference" "TP115"
			(at -0.5 1.800001 0)
			(layer "B.SilkS")
			(effects
				(font
					(size 0.7 0.7)
					(thickness 0.15)
				)
				(justify right top mirror)
			)
		)
		(property "Value" "TP_0.75mm_SMD"
			(at 0 -1.2 0)
			(layer "B.Fab")
			(effects
				(font
					(size 0.7 0.7)
					(thickness 0.15)
				)
				(justify right top mirror)
			)
		)
		(property "Description" "SMT test point"
			(at 0 0 0)
			(layer "B.Fab")
			(hide yes)
			(effects
				(font
					(size 1.27 1.27)
					(thickness 0.15)
				)
				(justify mirror)
			)
		)
		(property "MPN" ""
			(at 0 0 180)
			(unlocked yes)
			(layer "B.Fab")
			(hide yes)
			(effects
				(font
					(size 1 1)
					(thickness 0.15)
				)
				(justify mirror)
			)
		)
		(property "Manufacturer" ""
			(at 0 0 180)
			(unlocked yes)
			(layer "B.Fab")
			(hide yes)
			(effects
				(font
					(size 1 1)
					(thickness 0.15)
				)
				(justify mirror)
			)
		)
		(property "Author" "Antmicro"
			(at 0 0 180)
			(unlocked yes)
			(layer "B.Fab")
			(hide yes)
			(effects
				(font
					(size 1 1)
					(thickness 0.15)
				)
				(justify mirror)
			)
		)
		(property "License" "Apache-2.0"
			(at 0 0 180)
			(unlocked yes)
			(layer "B.Fab")
			(hide yes)
			(effects
				(font
					(size 1 1)
					(thickness 0.15)
				)
				(justify mirror)
			)
		)
		(sheetname "/Expansion connector/")
		(sheetfile "expansion_connector.kicad_sch")
		(attr exclude_from_pos_files exclude_from_bom)
		(fp_circle
			(center 0 0)
			(end 0.475 0)
			(stroke
				(width 0.05)
				(type default)
			)
			(fill no)
			(layer "B.CrtYd")
		)
		(fp_text user "License: Apache-2.0"
			(at -0.4 -5.101 0)
			(layer "B.Fab")
			(effects
				(font
					(size 0.7 0.7)
					(thickness 0.15)
				)
				(justify right top mirror)
			)
		)
		(fp_text user "Author: Antmicro"
			(at -0.4 -3.901 0)
			(layer "B.Fab")
			(effects
				(font
					(size 0.7 0.7)
					(thickness 0.15)
				)
				(justify right top mirror)
			)
		)
		(fp_text user "${REFERENCE}"
			(at -0.4 -2.7 0)
			(layer "B.Fab")
			(effects
				(font
					(size 0.7 0.7)
					(thickness 0.15)
				)
				(justify right top mirror)
			)
		)
		(pad "1" smd circle
			(at 0 0)
			(size 0.75 0.75)
			(layers "B.Cu" "B.Mask")
			(net 709 "Net-(J18-PadL33)")
			(pinfunction "1")
			(pintype "passive")
		)
	)
	(footprint "antmicro-footprints:C_0402_1005Metric"
		(layer "B.Cu")
		(at 178.405 78.175 180)
		(descr "Capacitor SMD 0402")
		(tags "capacitor SMD 0402")
		(property "Reference" "C264"
			(at 3.605 -0.425 0)
			(layer "B.SilkS")
			(effects
				(font
					(size 0.7 0.7)
					(thickness 0.15)
				)
				(justify left bottom mirror)
			)
		)
		(property "Value" "C_100n_0402"
			(at -1.022927 -2.155213 0)
			(layer "B.Fab")
			(effects
				(font
					(size 0.7 0.7)
					(thickness 0.15)
				)
				(justify left bottom mirror)
			)
		)
		(property "Datasheet" "https://www.murata.com/products/productdetail?partno=GRM155R61H104KE14%23"
			(at 0 0 0)
			(layer "B.Fab")
			(hide yes)
			(effects
				(font
					(size 1.27 1.27)
					(thickness 0.15)
				)
				(justify mirror)
			)
		)
		(property "Description" "SMD Multilayer Ceramic Capacitor, 0.1 µF, 50 V, 0402 [1005 Metric], ± 10%, X5R, GRM Series"
			(at 0 0 0)
			(layer "B.Fab")
			(hide yes)
			(effects
				(font
					(size 1.27 1.27)
					(thickness 0.15)
				)
				(justify mirror)
			)
		)
		(property "MPN" "GRM155R61H104KE14D"
			(at 0 0 0)
			(unlocked yes)
			(layer "B.Fab")
			(hide yes)
			(effects
				(font
					(size 1 1)
					(thickness 0.15)
				)
				(justify mirror)
			)
		)
		(property "Val" "100n"
			(at 0 0 0)
			(unlocked yes)
			(layer "B.Fab")
			(hide yes)
			(effects
				(font
					(size 1 1)
					(thickness 0.15)
				)
				(justify mirror)
			)
		)
		(property "Voltage" "50V"
			(at 0 0 0)
			(unlocked yes)
			(layer "B.Fab")
			(hide yes)
			(effects
				(font
					(size 1 1)
					(thickness 0.15)
				)
				(justify mirror)
			)
		)
		(property "Dielectric" "X5R"
			(at 0 0 0)
			(unlocked yes)
			(layer "B.Fab")
			(hide yes)
			(effects
				(font
					(size 1 1)
					(thickness 0.15)
				)
				(justify mirror)
			)
		)
		(property "Manufacturer" "Murata"
			(at 0 0 0)
			(unlocked yes)
			(layer "B.Fab")
			(hide yes)
			(effects
				(font
					(size 1 1)
					(thickness 0.15)
				)
				(justify mirror)
			)
		)
		(property "License" "Apache-2.0"
			(at 0 0 0)
			(unlocked yes)
			(layer "B.Fab")
			(hide yes)
			(effects
				(font
					(size 1 1)
					(thickness 0.15)
				)
				(justify mirror)
			)
		)
		(property "Author" "Antmicro"
			(at 0 0 0)
			(unlocked yes)
			(layer "B.Fab")
			(hide yes)
			(effects
				(font
					(size 1 1)
					(thickness 0.15)
				)
				(justify mirror)
			)
		)
		(sheetname "/Power/")
		(sheetfile "power.kicad_sch")
		(attr smd)
		(fp_rect
			(start -0.925 0.47)
			(end 0.925 -0.47)
			(stroke
				(width 0.05)
				(type default)
			)
			(fill no)
			(layer "B.CrtYd")
		)
		(fp_line
			(start 0.504 0.25)
			(end 0.504 -0.248)
			(stroke
				(width 0.15)
				(type solid)
			)
			(layer "B.Fab")
		)
		(fp_line
			(start 0.504 -0.248)
			(end -0.494 -0.248)
			(stroke
				(width 0.15)
				(type solid)
			)
			(layer "B.Fab")
		)
		(fp_line
			(start -0.494 0.25)
			(end 0.504 0.25)
			(stroke
				(width 0.15)
				(type solid)
			)
			(layer "B.Fab")
		)
		(fp_line
			(start -0.494 -0.248)
			(end -0.494 0.25)
			(stroke
				(width 0.15)
				(type solid)
			)
			(layer "B.Fab")
		)
		(fp_text user "License: Apache-2.0"
			(at -0.939 -5.799 0)
			(layer "B.Fab")
			(effects
				(font
					(size 0.7 0.7)
					(thickness 0.15)
				)
				(justify left bottom mirror)
			)
		)
		(fp_text user "Author: Antmicro"
			(at -0.939 -3.399 0)
			(layer "B.Fab")
			(effects
				(font
					(size 0.7 0.7)
					(thickness 0.15)
				)
				(justify left bottom mirror)
			)
		)
		(fp_text user "${REFERENCE}"
			(at -0.939 -4.599 0)
			(layer "B.Fab")
			(effects
				(font
					(size 0.7 0.7)
					(thickness 0.15)
				)
				(justify left bottom mirror)
			)
		)
		(pad "1" smd roundrect
			(at -0.48 0 180)
			(size 0.59 0.64)
			(layers "B.Cu" "B.Mask" "B.Paste")
			(roundrect_rratio 0.25)
			(net 1 "GND")
			(pintype "passive")
		)
		(pad "2" smd roundrect
			(at 0.48 0 180)
			(size 0.59 0.64)
			(layers "B.Cu" "B.Mask" "B.Paste")
			(roundrect_rratio 0.25)
			(net 904 "+20V")
			(pintype "passive")
		)
	)
	(footprint "antmicro-footprints:R_0402_1005Metric"
		(layer "B.Cu")
		(at 217.7 86.7 -90)
		(descr "Resistor SMD 0402")
		(tags "resistor SMD 0402")
		(property "Reference" "R133"
			(at -0.9 -2.5 90)
			(layer "B.SilkS")
			(effects
				(font
					(size 0.7 0.7)
					(thickness 0.15)
				)
				(justify left bottom mirror)
			)
		)
		(property "Value" "R_1k_0402"
			(at -1.011843 -1.772046 90)
			(layer "B.Fab")
			(effects
				(font
					(size 0.7 0.7)
					(thickness 0.15)
				)
				(justify left bottom mirror)
			)
		)
		(property "Datasheet" "https://www.bourns.com/docs/product-datasheets/cr.pdf"
			(at 0 0 90)
			(layer "B.Fab")
			(hide yes)
			(effects
				(font
					(size 1.27 1.27)
					(thickness 0.15)
				)
				(justify mirror)
			)
		)
		(property "Description" "SMD Chip Resistor, 1 kohm, ± 1%, 63 mW, 0402 [1005 Metric], Thick Film, General Purpose"
			(at 0 0 90)
			(layer "B.Fab")
			(hide yes)
			(effects
				(font
					(size 1.27 1.27)
					(thickness 0.15)
				)
				(justify mirror)
			)
		)
		(property "Manufacturer" "Bourns"
			(at 0 0 90)
			(unlocked yes)
			(layer "B.Fab")
			(hide yes)
			(effects
				(font
					(size 1 1)
					(thickness 0.15)
				)
				(justify mirror)
			)
		)
		(property "MPN" "CR0402-FX-1001GLF"
			(at 0 0 90)
			(unlocked yes)
			(layer "B.Fab")
			(hide yes)
			(effects
				(font
					(size 1 1)
					(thickness 0.15)
				)
				(justify mirror)
			)
		)
		(property "Val" "1k"
			(at 0 0 90)
			(unlocked yes)
			(layer "B.Fab")
			(hide yes)
			(effects
				(font
					(size 1 1)
					(thickness 0.15)
				)
				(justify mirror)
			)
		)
		(property "License" "Apache-2.0"
			(at 0 0 90)
			(unlocked yes)
			(layer "B.Fab")
			(hide yes)
			(effects
				(font
					(size 1 1)
					(thickness 0.15)
				)
				(justify mirror)
			)
		)
		(property "Author" "Antmicro"
			(at 0 0 90)
			(unlocked yes)
			(layer "B.Fab")
			(hide yes)
			(effects
				(font
					(size 1 1)
					(thickness 0.15)
				)
				(justify mirror)
			)
		)
		(property "Tolerance" "1%"
			(at 0 0 90)
			(unlocked yes)
			(layer "B.Fab")
			(hide yes)
			(effects
				(font
					(size 1 1)
					(thickness 0.15)
				)
				(justify mirror)
			)
		)
		(sheetname "/USB DP Alt mode/")
		(sheetfile "usb_dp.kicad_sch")
		(attr smd)
		(fp_poly
			(pts
				(xy -0.925 0.47) (xy 0.925 0.47) (xy 0.925 -0.47) (xy -0.925 -0.47)
			)
			(stroke
				(width 0.05)
				(type default)
			)
			(fill no)
			(layer "B.CrtYd")
		)
		(fp_poly
			(pts
				(xy -0.5 0.25) (xy 0.5 0.25) (xy 0.5 -0.25) (xy -0.5 -0.25)
			)
			(stroke
				(width 0.15)
				(type solid)
			)
			(fill no)
			(layer "B.Fab")
		)
		(fp_text user "License: Apache-2.0"
			(at -0.949999 -5.169 90)
			(layer "B.Fab")
			(effects
				(font
					(size 0.7 0.7)
					(thickness 0.15)
				)
				(justify left bottom mirror)
			)
		)
		(fp_text user "${REFERENCE}"
			(at -0.95 -3.168 90)
			(layer "B.Fab")
			(effects
				(font
					(size 0.7 0.7)
					(thickness 0.15)
				)
				(justify left bottom mirror)
			)
		)
		(fp_text user "Author: Antmicro"
			(at -0.95 -4.169 90)
			(layer "B.Fab")
			(effects
				(font
					(size 0.7 0.7)
					(thickness 0.15)
				)
				(justify left bottom mirror)
			)
		)
		(pad "1" smd roundrect
			(at -0.48 0 270)
			(size 0.59 0.64)
			(layers "B.Cu" "B.Mask" "B.Paste")
			(roundrect_rratio 0.25)
			(net 965 "/USB DP Alt mode/USBC1_SSEQ1")
			(pintype "passive")
		)
		(pad "2" smd roundrect
			(at 0.48 0 270)
			(size 0.59 0.64)
			(layers "B.Cu" "B.Mask" "B.Paste")
			(roundrect_rratio 0.25)
			(net 1 "GND")
			(pintype "passive")
		)
	)
	(footprint "antmicro-footprints:C_0603_1608Metric_EIA"
		(layer "B.Cu")
		(at 109.61 69.49)
		(descr "Capacitor SMD 0603, IPC-7351 Density Level A")
		(tags "Capacitor 0603")
		(property "Reference" "C22"
			(at 1.19 -0.89 180)
			(layer "B.SilkS")
			(effects
				(font
					(size 0.7 0.7)
					(thickness 0.15)
				)
				(justify left bottom mirror)
			)
		)
		(property "Value" "C_22u_16V_0603"
			(at -1.42757 -1.770288 180)
			(layer "B.Fab")
			(effects
				(font
					(size 0.7 0.7)
					(thickness 0.15)
				)
				(justify left bottom mirror)
			)
		)
		(property "Datasheet" "https://product.samsungsem.com/mlcc/CL10A226MO7JZN.do"
			(at 0 0 180)
			(layer "B.Fab")
			(hide yes)
			(effects
				(font
					(size 1.27 1.27)
					(thickness 0.15)
				)
				(justify mirror)
			)
		)
		(property "Description" "SMD Multilayer Ceramic Capacitor"
			(at 0 0 180)
			(layer "B.Fab")
			(hide yes)
			(effects
				(font
					(size 1.27 1.27)
					(thickness 0.15)
				)
				(justify mirror)
			)
		)
		(property "MPN" "CL10A226MO7JZNC"
			(at 0 0 0)
			(unlocked yes)
			(layer "B.Fab")
			(hide yes)
			(effects
				(font
					(size 1 1)
					(thickness 0.15)
				)
				(justify mirror)
			)
		)
		(property "Manufacturer" "Samsung Electro-Mechanics"
			(at 0 0 0)
			(unlocked yes)
			(layer "B.Fab")
			(hide yes)
			(effects
				(font
					(size 1 1)
					(thickness 0.15)
				)
				(justify mirror)
			)
		)
		(property "License" "Apache-2.0"
			(at 0 0 0)
			(unlocked yes)
			(layer "B.Fab")
			(hide yes)
			(effects
				(font
					(size 1 1)
					(thickness 0.15)
				)
				(justify mirror)
			)
		)
		(property "Author" "Antmicro"
			(at 0 0 0)
			(unlocked yes)
			(layer "B.Fab")
			(hide yes)
			(effects
				(font
					(size 1 1)
					(thickness 0.15)
				)
				(justify mirror)
			)
		)
		(property "Val" "22u"
			(at 0 0 0)
			(unlocked yes)
			(layer "B.Fab")
			(hide yes)
			(effects
				(font
					(size 1 1)
					(thickness 0.15)
				)
				(justify mirror)
			)
		)
		(property "Voltage" "16V"
			(at 0 0 0)
			(unlocked yes)
			(layer "B.Fab")
			(hide yes)
			(effects
				(font
					(size 1 1)
					(thickness 0.15)
				)
				(justify mirror)
			)
		)
		(property "Dielectric" "X7R"
			(at 0 0 0)
			(unlocked yes)
			(layer "B.Fab")
			(hide yes)
			(effects
				(font
					(size 1 1)
					(thickness 0.15)
				)
				(justify mirror)
			)
		)
		(property "Public" "False"
			(at 0 0 0)
			(unlocked yes)
			(layer "B.Fab")
			(hide yes)
			(effects
				(font
					(size 1 1)
					(thickness 0.15)
				)
				(justify mirror)
			)
		)
		(sheetname "/SoM_Power/")
		(sheetfile "som_power.kicad_sch")
		(attr smd)
		(fp_line
			(start -0.15 -0.55)
			(end 0.15 -0.55)
			(stroke
				(width 0.15)
				(type solid)
			)
			(layer "B.SilkS")
		)
		(fp_line
			(start -0.15 0.55)
			(end 0.15 0.55)
			(stroke
				(width 0.15)
				(type solid)
			)
			(layer "B.SilkS")
		)
		(fp_rect
			(start -1.25 0.65)
			(end 1.25 -0.65)
			(stroke
				(width 0.05)
				(type solid)
			)
			(fill no)
			(layer "B.CrtYd")
		)
		(fp_rect
			(start -0.8 0.45)
			(end 0.8 -0.45)
			(stroke
				(width 0.15)
				(type solid)
			)
			(fill no)
			(layer "B.Fab")
		)
		(fp_text user "Author: Antmicro"
			(at -1.682 -4.894 180)
			(layer "B.Fab")
			(effects
				(font
					(size 0.7 0.7)
					(thickness 0.15)
				)
				(justify left bottom mirror)
			)
		)
		(fp_text user "${REFERENCE}"
			(at -1.682 -3.895 180)
			(layer "B.Fab")
			(effects
				(font
					(size 0.7 0.7)
					(thickness 0.15)
				)
				(justify left bottom mirror)
			)
		)
		(fp_text user "License: Apache-2.0"
			(at -1.682 -5.895 180)
			(layer "B.Fab")
			(effects
				(font
					(size 0.7 0.7)
					(thickness 0.15)
				)
				(justify left bottom mirror)
			)
		)
		(pad "1" smd roundrect
			(at -0.7 0)
			(size 0.8 1.1)
			(layers "B.Cu" "B.Mask" "B.Paste")
			(roundrect_rratio 0.2)
			(net 1 "GND")
			(pintype "passive")
		)
		(pad "2" smd roundrect
			(at 0.7 0)
			(size 0.8 1.1)
			(layers "B.Cu" "B.Mask" "B.Paste")
			(roundrect_rratio 0.2)
			(net 213 "+5V_SOM")
			(pintype "passive")
		)
	)
)
